(kicad_pcb
	(version 20260206)
	(generator "pcbnew")
	(generator_version "10.0")
	(general
		(thickness 1.6)
		(legacy_teardrops no)
	)
	(paper "A4")
	(title_block
		(title "03242023_DA0F0TMBIJ0_F0T_Motherboard_J_brd_V01_OCP.brd")
		(comment 1 "Grand Teton / footprints 1949-1951 of 6105")
	)
	(layers
		(0 "F.Cu" signal "TOP")
		(4 "In1.Cu" signal "GND")
		(6 "In2.Cu" signal "IN1")
		(8 "In3.Cu" signal "GND1")
		(10 "In4.Cu" signal "IN2")
		(12 "In5.Cu" signal "GND2")
		(14 "In6.Cu" signal "IN3")
		(16 "In7.Cu" signal "GND3")
		(18 "In8.Cu" signal "VCC")
		(20 "In9.Cu" signal "VCC1")
		(22 "In10.Cu" signal "GND4")
		(24 "In11.Cu" signal "IN4")
		(26 "In12.Cu" signal "GND5")
		(28 "In13.Cu" signal "IN5")
		(30 "In14.Cu" signal "GND6")
		(32 "In15.Cu" signal "IN6")
		(34 "In16.Cu" signal "GND7")
		(2 "B.Cu" signal "BOTTOM")
		(9 "F.Adhes" user "F.Adhesive")
		(11 "B.Adhes" user "B.Adhesive")
		(13 "F.Paste" user "Package Geometry/Pastemask Top")
		(15 "B.Paste" user "Package Geometry/Pastemask Bottom")
		(5 "F.SilkS" user "Ref Des/Silkscreen Top")
		(7 "B.SilkS" user "Ref Des/Silkscreen Bottom")
		(1 "F.Mask" user "Board Geometry/Soldermask Top")
		(3 "B.Mask" user "Board Geometry/Soldermask Bottom")
		(17 "Dwgs.User" user "User.Drawings")
		(19 "Cmts.User" user "User.Comments")
		(21 "Eco1.User" user "User.Eco1")
		(23 "Eco2.User" user "User.Eco2")
		(25 "Edge.Cuts" user "Board Geometry/Outline")
		(27 "Margin" user)
		(31 "F.CrtYd" user "Package Geometry/Place Bound Top")
		(29 "B.CrtYd" user "Package Geometry/Place Bound Bottom")
		(35 "F.Fab" user "Ref Des/Assembly Top")
		(33 "B.Fab" user "Ref Des/Assembly Bottom")
	)
	(footprint ""
		(layer "F.Cu")
		(at 189.79769 -36.0807)
		(property "Reference" "R1856"
			(at 0 0 0)
			(layer "F.SilkS")
			(hide yes)
			(effects
				(font
					(size 1.27 1.27)
				)
			)
		)
		(property "Value" ""
			(at 0 0 0)
			(layer "F.Fab")
			(effects
				(font
					(size 1.27 1.27)
				)
			)
		)
		(duplicate_pad_numbers_are_jumpers no)
		(fp_line
			(start -0.7874 -0.4064)
			(end 0.7874 -0.4064)
			(stroke
				(width 0.1524)
				(type default)
			)
			(layer "F.SilkS")
		)
		(fp_line
			(start -0.7874 0.4064)
			(end -0.7874 -0.4064)
			(stroke
				(width 0.1524)
				(type default)
			)
			(layer "F.SilkS")
		)
		(fp_line
			(start 0.7874 -0.4064)
			(end 0.7874 0.4064)
			(stroke
				(width 0.1524)
				(type default)
			)
			(layer "F.SilkS")
		)
		(fp_line
			(start 0.7874 0.4064)
			(end -0.7874 0.4064)
			(stroke
				(width 0.1524)
				(type default)
			)
			(layer "F.SilkS")
		)
		(fp_line
			(start -0.67945 -0.305054)
			(end -0.12065 -0.305054)
			(stroke
				(width 0.1)
				(type default)
			)
			(layer "F.Fab")
		)
		(fp_line
			(start -0.67945 0.3048)
			(end -0.67945 -0.305054)
			(stroke
				(width 0.1)
				(type default)
			)
			(layer "F.Fab")
		)
		(fp_line
			(start -0.12065 -0.305054)
			(end -0.12065 -0.2794)
			(stroke
				(width 0.1)
				(type default)
			)
			(layer "F.Fab")
		)
		(fp_line
			(start -0.12065 -0.2794)
			(end 0.12065 -0.2794)
			(stroke
				(width 0.1)
				(type default)
			)
			(layer "F.Fab")
		)
		(fp_line
			(start -0.12065 0.2794)
			(end -0.12065 0.3048)
			(stroke
				(width 0.1)
				(type default)
			)
			(layer "F.Fab")
		)
		(fp_line
			(start -0.12065 0.3048)
			(end -0.67945 0.3048)
			(stroke
				(width 0.1)
				(type default)
			)
			(layer "F.Fab")
		)
		(fp_line
			(start 0.120396 0.2794)
			(end -0.12065 0.2794)
			(stroke
				(width 0.1)
				(type default)
			)
			(layer "F.Fab")
		)
		(fp_line
			(start 0.120396 0.3048)
			(end 0.120396 0.2794)
			(stroke
				(width 0.1)
				(type default)
			)
			(layer "F.Fab")
		)
		(fp_line
			(start 0.12065 -0.3048)
			(end 0.67945 -0.3048)
			(stroke
				(width 0.1)
				(type default)
			)
			(layer "F.Fab")
		)
		(fp_line
			(start 0.12065 -0.2794)
			(end 0.12065 -0.3048)
			(stroke
				(width 0.1)
				(type default)
			)
			(layer "F.Fab")
		)
		(fp_line
			(start 0.67945 -0.3048)
			(end 0.67945 0.3048)
			(stroke
				(width 0.1)
				(type default)
			)
			(layer "F.Fab")
		)
		(fp_line
			(start 0.67945 0.3048)
			(end 0.120396 0.3048)
			(stroke
				(width 0.1)
				(type default)
			)
			(layer "F.Fab")
		)
		(pad "1" smd circle
			(at -0.40005 0)
			(size 0 0)
			(layers "F.Cu" "F.Mask" "F.Paste")
			(net "FM_SCM_PRSNT1_N")
		)
		(pad "2" smd circle
			(at 0.40005 0)
			(size 0 0)
			(layers "F.Cu" "F.Mask" "F.Paste")
			(net "FM_SCM_PRSNT1_R_N")
		)
	)
	(footprint ""
		(layer "F.Cu")
		(at 328.523092 -73.509378 90)
		(property "Reference" "R4303"
			(at 0 0 90)
			(layer "F.SilkS")
			(hide yes)
			(effects
				(font
					(size 1.27 1.27)
				)
			)
		)
		(property "Value" ""
			(at 0 0 90)
			(layer "F.Fab")
			(effects
				(font
					(size 1.27 1.27)
				)
			)
		)
		(duplicate_pad_numbers_are_jumpers no)
		(fp_line
			(start 0.7874 -0.4064)
			(end 0.7874 0.4064)
			(stroke
				(width 0.1524)
				(type default)
			)
			(layer "F.SilkS")
		)
		(fp_line
			(start -0.7874 -0.4064)
			(end 0.7874 -0.4064)
			(stroke
				(width 0.1524)
				(type default)
			)
			(layer "F.SilkS")
		)
		(fp_line
			(start 0.7874 0.4064)
			(end -0.7874 0.4064)
			(stroke
				(width 0.1524)
				(type default)
			)
			(layer "F.SilkS")
		)
		(fp_line
			(start -0.7874 0.4064)
			(end -0.7874 -0.4064)
			(stroke
				(width 0.1524)
				(type default)
			)
			(layer "F.SilkS")
		)
		(fp_line
			(start -0.12065 -0.305054)
			(end -0.12065 -0.2794)
			(stroke
				(width 0.1)
				(type default)
			)
			(layer "F.Fab")
		)
		(fp_line
			(start -0.67945 -0.305054)
			(end -0.12065 -0.305054)
			(stroke
				(width 0.1)
				(type default)
			)
			(layer "F.Fab")
		)
		(fp_line
			(start 0.67945 -0.3048)
			(end 0.67945 0.3048)
			(stroke
				(width 0.1)
				(type default)
			)
			(layer "F.Fab")
		)
		(fp_line
			(start 0.12065 -0.3048)
			(end 0.67945 -0.3048)
			(stroke
				(width 0.1)
				(type default)
			)
			(layer "F.Fab")
		)
		(fp_line
			(start 0.12065 -0.2794)
			(end 0.12065 -0.3048)
			(stroke
				(width 0.1)
				(type default)
			)
			(layer "F.Fab")
		)
		(fp_line
			(start -0.12065 -0.2794)
			(end 0.12065 -0.2794)
			(stroke
				(width 0.1)
				(type default)
			)
			(layer "F.Fab")
		)
		(fp_line
			(start 0.120396 0.2794)
			(end -0.12065 0.2794)
			(stroke
				(width 0.1)
				(type default)
			)
			(layer "F.Fab")
		)
		(fp_line
			(start -0.12065 0.2794)
			(end -0.12065 0.3048)
			(stroke
				(width 0.1)
				(type default)
			)
			(layer "F.Fab")
		)
		(fp_line
			(start 0.67945 0.3048)
			(end 0.120396 0.3048)
			(stroke
				(width 0.1)
				(type default)
			)
			(layer "F.Fab")
		)
		(fp_line
			(start 0.120396 0.3048)
			(end 0.120396 0.2794)
			(stroke
				(width 0.1)
				(type default)
			)
			(layer "F.Fab")
		)
		(fp_line
			(start -0.12065 0.3048)
			(end -0.67945 0.3048)
			(stroke
				(width 0.1)
				(type default)
			)
			(layer "F.Fab")
		)
		(fp_line
			(start -0.67945 0.3048)
			(end -0.67945 -0.305054)
			(stroke
				(width 0.1)
				(type default)
			)
			(layer "F.Fab")
		)
		(pad "1" smd circle
			(at -0.40005 0 90)
			(size 0 0)
			(layers "F.Cu" "F.Mask" "F.Paste")
			(net "CLK_100M_E1S_0_R_DP")
		)
		(pad "2" smd circle
			(at 0.40005 0 90)
			(size 0 0)
			(layers "F.Cu" "F.Mask" "F.Paste")
			(net "CLK_100M_E1S_0_DP")
		)
	)
	(footprint ""
		(layer "F.Cu")
		(at 353.266248 -249.320304 -90)
		(property "Reference" "C1034"
			(at 0 0 270)
			(layer "F.SilkS")
			(hide yes)
			(effects
				(font
					(size 1.27 1.27)
				)
			)
		)
		(property "Value" ""
			(at 0 0 270)
			(layer "F.Fab")
			(effects
				(font
					(size 1.27 1.27)
				)
			)
		)
		(duplicate_pad_numbers_are_jumpers no)
		(fp_line
			(start -0.7874 0.4064)
			(end -0.7874 -0.4064)
			(stroke
				(width 0.1524)
				(type default)
			)
			(layer "F.SilkS")
		)
		(fp_line
			(start 0.7874 0.4064)
			(end -0.7874 0.4064)
			(stroke
				(width 0.1524)
				(type default)
			)
			(layer "F.SilkS")
		)
		(fp_line
			(start -0.7874 -0.4064)
			(end 0.7874 -0.4064)
			(stroke
				(width 0.1524)
				(type default)
			)
			(layer "F.SilkS")
		)
		(fp_line
			(start 0.7874 -0.4064)
			(end 0.7874 0.4064)
			(stroke
				(width 0.1524)
				(type default)
			)
			(layer "F.SilkS")
		)
		(fp_line
			(start -0.67945 0.3048)
			(end -0.67945 -0.305054)
			(stroke
				(width 0.1)
				(type default)
			)
			(layer "F.Fab")
		)
		(fp_line
			(start -0.12065 0.3048)
			(end -0.67945 0.3048)
			(stroke
				(width 0.1)
				(type default)
			)
			(layer "F.Fab")
		)
		(fp_line
			(start 0.120396 0.3048)
			(end 0.120396 0.2794)
			(stroke
				(width 0.1)
				(type default)
			)
			(layer "F.Fab")
		)
		(fp_line
			(start 0.67945 0.3048)
			(end 0.120396 0.3048)
			(stroke
				(width 0.1)
				(type default)
			)
			(layer "F.Fab")
		)
		(fp_line
			(start -0.12065 0.2794)
			(end -0.12065 0.3048)
			(stroke
				(width 0.1)
				(type default)
			)
			(layer "F.Fab")
		)
		(fp_line
			(start 0.120396 0.2794)
			(end -0.12065 0.2794)
			(stroke
				(width 0.1)
				(type default)
			)
			(layer "F.Fab")
		)
		(fp_line
			(start -0.12065 -0.2794)
			(end 0.12065 -0.2794)
			(stroke
				(width 0.1)
				(type default)
			)
			(layer "F.Fab")
		)
		(fp_line
			(start 0.12065 -0.2794)
			(end 0.12065 -0.3048)
			(stroke
				(width 0.1)
				(type default)
			)
			(layer "F.Fab")
		)
		(fp_line
			(start 0.12065 -0.3048)
			(end 0.67945 -0.3048)
			(stroke
				(width 0.1)
				(type default)
			)
			(layer "F.Fab")
		)
		(fp_line
			(start 0.67945 -0.3048)
			(end 0.67945 0.3048)
			(stroke
				(width 0.1)
				(type default)
			)
			(layer "F.Fab")
		)
		(fp_line
			(start -0.67945 -0.305054)
			(end -0.12065 -0.305054)
			(stroke
				(width 0.1)
				(type default)
			)
			(layer "F.Fab")
		)
		(fp_line
			(start -0.12065 -0.305054)
			(end -0.12065 -0.2794)
			(stroke
				(width 0.1)
				(type default)
			)
			(layer "F.Fab")
		)
		(pad "1" smd circle
			(at -0.40005 0 270)
			(size 0 0)
			(layers "F.Cu" "F.Mask" "F.Paste")
			(net "PVCCIN_CPU0")
		)
		(pad "2" smd circle
			(at 0.40005 0 270)
			(size 0 0)
			(layers "F.Cu" "F.Mask" "F.Paste")
			(net "GND")
		)
	)
)
